FILE_TYPE = CONNECTIVITY;
{Allegro Design Entry HDL 17.4-2019 S026 (4007227) 1/17/2022}
"PAGE_NUMBER" = 416;
0"NC";
1"P5E_CPU0_P2_RX_DP<15:8>";
2"P5E_CPU0_P2_RX_DP<7:0>";
3"P5E_CPU0_P2_RX_DN<15:8>";
4"P5E_CPU0_P2_RX_DN<7:0>";
5"P5E_CPU0_P2_RX_DP<15>";
6"P5E_CPU0_P2_RX_DN<15>";
7"P5E_CPU0_P2_RX_DP<14>";
8"P5E_CPU0_P2_RX_DN<14>";
9"P5E_CPU0_P2_RX_DP<2>";
10"P5E_CPU0_P2_RX_DN<6>";
11"P5E_CPU0_P2_RX_DN<2>";
12"P5E_CPU0_P2_RX_DN<5>";
13"P5E_CPU0_P2_RX_DN<4>";
14"P5E_CPU0_P2_RX_DN<1>";
15"P5E_CPU0_P2_RX_DN<0>";
16"P5E_CPU0_P2_RX_DN<3>";
17"P5E_CPU0_P2_RX_DN<7>";
18"P5E_CPU0_P2_RX_DN<12>";
19"P5E_CPU0_P2_RX_DN<11>";
20"P5E_CPU0_P2_RX_DN<8>";
21"P5E_CPU0_P2_RX_DN<13>";
22"P5E_CPU0_P2_RX_DN<10>";
23"P5E_CPU0_P2_RX_DN<9>";
24"P5E_CPU0_P2_RX_DP<4>";
25"P5E_CPU0_P2_RX_DP<5>";
26"P5E_CPU0_P2_RX_DP<13>";
27"P5E_CPU0_P2_RX_DP<10>";
28"P5E_CPU0_P2_RX_DP<3>";
29"P5E_CPU0_P2_RX_DP<1>";
30"P5E_CPU0_P2_RX_DP<0>";
31"P5E_CPU0_P2_RX_DP<7>";
32"P5E_CPU0_P2_RX_DP<6>";
33"P5E_CPU0_P2_RX_DP<8>";
34"P5E_CPU0_P2_RX_DP<11>";
35"P5E_CPU0_P2_RX_DP<12>";
36"P5E_CPU0_P2_RX_DP<9>";
%"PT5161LRS"
"6","(-7750,4400)","0","pure_quanta","I1";
;
LOCATION"U6012"
$SEC"6"
CDS_SEC"6"
VALUE"PT5161LRS"
PART_TYPE"SMLF"
MATERIAL"IC"
NEEDS_NO_SIZE"TRUE"
CDS_LMAN_SYM_OUTLINE"-350,1450,300,-1400"
CDS_LIB"pure_quanta"
PART_NUMBER"AJ051610U03";
"A_PETN7"
$PN"CC29"20;
"A_PETP7"
$PN"CA26"33;
"A_PETN6"
$PN"BT29"23;
"A_PETP6"
$PN"BP26"36;
"A_PETN5"
$PN"BJ29"22;
"A_PETP5"
$PN"BG26"27;
"A_PETN4"
$PN"BB29"19;
"A_PETP4"
$PN"AY26"34;
"A_PETN3"
$PN"AR29"18;
"A_PETP3"
$PN"AN26"35;
"A_PETN2"
$PN"AH29"21;
"A_PETP2"
$PN"AF26"26;
"A_PETN1"
$PN"AA29"8;
"A_PETP1"
$PN"W26"7;
"A_PETN0"
$PN"P29"6;
"A_PETP0"
$PN"M26"5;
%"TAP"
"1","(-6525,4150)","0","standard","I10";
;
CDS_LIB"standard"
BODY_TYPE"PLUMBING"
HDL_TAP"TRUE";
"B \NAC \NWC"3;
"S \NAC"
BN"11"19;
%"TAP"
"1","(-6525,4500)","0","standard","I11";
;
CDS_LIB"standard"
BODY_TYPE"PLUMBING"
HDL_TAP"TRUE";
"B \NAC \NWC"3;
"S \NAC"
BN"12"18;
%"TAP"
"1","(-6725,4950)","0","standard","I12";
;
CDS_LIB"standard"
BODY_TYPE"PLUMBING"
HDL_TAP"TRUE";
"B \NAC \NWC"1;
"S \NAC"
BN"13"26;
%"TAP"
"1","(-6725,5300)","0","standard","I13";
;
CDS_LIB"standard"
BODY_TYPE"PLUMBING"
HDL_TAP"TRUE";
"B \NAC \NWC"1;
"S \NAC"
BN"14"7;
%"TAP"
"1","(-6725,5650)","0","standard","I14";
;
CDS_LIB"standard"
BODY_TYPE"PLUMBING"
HDL_TAP"TRUE";
"B \NAC \NWC"1;
"S \NAC"
BN"15"5;
%"TAP"
"1","(-6525,4850)","0","standard","I15";
;
CDS_LIB"standard"
BODY_TYPE"PLUMBING"
HDL_TAP"TRUE";
"B \NAC \NWC"3;
"S \NAC"
BN"13"21;
%"TAP"
"1","(-6525,5200)","0","standard","I16";
;
CDS_LIB"standard"
BODY_TYPE"PLUMBING"
HDL_TAP"TRUE";
"B \NAC \NWC"3;
"S \NAC"
BN"14"8;
%"TAP"
"1","(-6525,5550)","0","standard","I17";
;
CDS_LIB"standard"
BODY_TYPE"PLUMBING"
HDL_TAP"TRUE";
"B \NAC \NWC"3;
"S \NAC"
BN"15"6;
%"TAP"
"1","(-6725,3200)","0","standard","I2";
;
CDS_LIB"standard"
BODY_TYPE"PLUMBING"
HDL_TAP"TRUE";
"B \NAC \NWC"1;
"S \NAC"
BN"8"33;
%"TAP"
"1","(-2200,3150)","0","standard","I20";
;
CDS_LIB"standard"
BODY_TYPE"PLUMBING"
HDL_TAP"TRUE";
"B \NAC \NWC"2;
"S \NAC"
BN"0"30;
%"TAP"
"1","(-2200,3500)","0","standard","I21";
;
CDS_LIB"standard"
BODY_TYPE"PLUMBING"
HDL_TAP"TRUE";
"B \NAC \NWC"2;
"S \NAC"
BN"1"29;
%"TAP"
"1","(-2200,3850)","0","standard","I22";
;
CDS_LIB"standard"
BODY_TYPE"PLUMBING"
HDL_TAP"TRUE";
"B \NAC \NWC"2;
"S \NAC"
BN"2"9;
%"TAP"
"1","(-2200,4200)","0","standard","I23";
;
CDS_LIB"standard"
BODY_TYPE"PLUMBING"
HDL_TAP"TRUE";
"B \NAC \NWC"2;
"S \NAC"
BN"3"28;
%"TAP"
"1","(-2200,4550)","0","standard","I24";
;
CDS_LIB"standard"
BODY_TYPE"PLUMBING"
HDL_TAP"TRUE";
"B \NAC \NWC"2;
"S \NAC"
BN"4"24;
%"TAP"
"1","(-2000,3050)","0","standard","I25";
;
CDS_LIB"standard"
BODY_TYPE"PLUMBING"
HDL_TAP"TRUE";
"B \NAC \NWC"4;
"S \NAC"
BN"0"15;
%"TAP"
"1","(-2000,3400)","0","standard","I26";
;
CDS_LIB"standard"
BODY_TYPE"PLUMBING"
HDL_TAP"TRUE";
"B \NAC \NWC"4;
"S \NAC"
BN"1"14;
%"TAP"
"1","(-2000,3750)","0","standard","I27";
;
CDS_LIB"standard"
BODY_TYPE"PLUMBING"
HDL_TAP"TRUE";
"B \NAC \NWC"4;
"S \NAC"
BN"2"11;
%"TAP"
"1","(-2000,4100)","0","standard","I28";
;
CDS_LIB"standard"
BODY_TYPE"PLUMBING"
HDL_TAP"TRUE";
"B \NAC \NWC"4;
"S \NAC"
BN"3"16;
%"TAP"
"1","(-2000,4450)","0","standard","I29";
;
CDS_LIB"standard"
BODY_TYPE"PLUMBING"
HDL_TAP"TRUE";
"B \NAC \NWC"4;
"S \NAC"
BN"4"13;
%"TAP"
"1","(-6725,3550)","0","standard","I3";
;
CDS_LIB"standard"
BODY_TYPE"PLUMBING"
HDL_TAP"TRUE";
"B \NAC \NWC"1;
"S \NAC"
BN"9"36;
%"TAP"
"1","(-2200,4900)","0","standard","I30";
;
CDS_LIB"standard"
BODY_TYPE"PLUMBING"
HDL_TAP"TRUE";
"B \NAC \NWC"2;
"S \NAC"
BN"5"25;
%"TAP"
"1","(-2200,5250)","0","standard","I31";
;
CDS_LIB"standard"
BODY_TYPE"PLUMBING"
HDL_TAP"TRUE";
"B \NAC \NWC"2;
"S \NAC"
BN"6"32;
%"TAP"
"1","(-2200,5600)","0","standard","I32";
;
CDS_LIB"standard"
BODY_TYPE"PLUMBING"
HDL_TAP"TRUE";
"B \NAC \NWC"2;
"S \NAC"
BN"7"31;
%"TAP"
"1","(-2000,4800)","0","standard","I33";
;
CDS_LIB"standard"
BODY_TYPE"PLUMBING"
HDL_TAP"TRUE";
"B \NAC \NWC"4;
"S \NAC"
BN"5"12;
%"TAP"
"1","(-2000,5150)","0","standard","I34";
;
CDS_LIB"standard"
BODY_TYPE"PLUMBING"
HDL_TAP"TRUE";
"B \NAC \NWC"4;
"S \NAC"
BN"6"10;
%"TAP"
"1","(-2000,5500)","0","standard","I35";
;
CDS_LIB"standard"
BODY_TYPE"PLUMBING"
HDL_TAP"TRUE";
"B \NAC \NWC"4;
"S \NAC"
BN"7"17;
%"PT5161LRS"
"7","(-3225,4350)","0","pure_quanta","I38";
;
LOCATION"U6012"
$SEC"7"
CDS_SEC"7"
PART_TYPE"SMLF"
VALUE"PT5161LRS"
MATERIAL"IC"
CDS_LIB"pure_quanta"
CDS_LMAN_SYM_OUTLINE"-350,1450,300,-1400"
NEEDS_NO_SIZE"TRUE"
PART_NUMBER"AJ051610U03";
"A_PETN15"
$PN"EW29"15;
"A_PETP15"
$PN"EU26"30;
"A_PETN14"
$PN"EM29"14;
"A_PETP14"
$PN"EK26"29;
"A_PETN13"
$PN"EE29"11;
"A_PETP13"
$PN"EC26"9;
"A_PETN12"
$PN"DV29"16;
"A_PETP12"
$PN"DT26"28;
"A_PETN11"
$PN"DL29"13;
"A_PETP11"
$PN"DJ26"24;
"A_PETN10"
$PN"DD29"12;
"A_PETP10"
$PN"DB26"25;
"A_PETN9"
$PN"CU29"10;
"A_PETP9"
$PN"CR26"32;
"A_PETN8"
$PN"CK29"17;
"A_PETP8"
$PN"CH26"31;
%"TAP"
"1","(-6525,3100)","0","standard","I4";
;
CDS_LIB"standard"
BODY_TYPE"PLUMBING"
HDL_TAP"TRUE";
"B \NAC \NWC"3;
"S \NAC"
BN"8"20;
%"TAP"
"1","(-6525,3450)","0","standard","I5";
;
CDS_LIB"standard"
BODY_TYPE"PLUMBING"
HDL_TAP"TRUE";
"B \NAC \NWC"3;
"S \NAC"
BN"9"23;
%"TAP"
"1","(-6725,3900)","0","standard","I6";
;
CDS_LIB"standard"
BODY_TYPE"PLUMBING"
HDL_TAP"TRUE";
"B \NAC \NWC"1;
"S \NAC"
BN"10"27;
%"TAP"
"1","(-6725,4250)","0","standard","I7";
;
CDS_LIB"standard"
BODY_TYPE"PLUMBING"
HDL_TAP"TRUE";
"B \NAC \NWC"1;
"S \NAC"
BN"11"34;
%"TAP"
"1","(-6725,4600)","0","standard","I8";
;
CDS_LIB"standard"
BODY_TYPE"PLUMBING"
HDL_TAP"TRUE";
"B \NAC \NWC"1;
"S \NAC"
BN"12"35;
%"TAP"
"1","(-6525,3800)","0","standard","I9";
;
CDS_LIB"standard"
BODY_TYPE"PLUMBING"
HDL_TAP"TRUE";
"B \NAC \NWC"3;
"S \NAC"
BN"10"22;
END.
